# BASEBOARD_FAB2 (Tioga Pass) — schematic netlist excerpt (pin names and nets, part order shuffled) for the footprints in the layout excerpt that follows; sources: Cadence DE-HDL packaged netlist, KiCad conversion of Wiwynn_Tioga_Pass_MB.brd

C25W93  CAP_A  0.1UF 16V 10% X7R  pkg 0402V  page 255 : A = P0V7_GTL2014_VREF_6 ; B = GND
C1M7  CAP  0.22UF 16V 10% X7R  pkg 0402  page 106 : A = P3E_CPU0_PE3_OCP_TXN<15> ; B = P3E_OCP_CPU0_PE3_C_TXN<15>
R4P15  RES  100.0 1% CHIP  pkg 0402  page 112 : A = PVCCIO_CPU0 ; B = XDP_CPU_MBP1_N

(kicad_pcb
	(version 20260206)
	(generator "pcbnew")
	(generator_version "10.0")
	(general
		(thickness 1.6)
		(legacy_teardrops no)
	)
	(paper "A4")
	(title_block
		(title "Wiwynn_Tioga_Pass_MB.brd")
		(comment 1 "Tioga Pass / footprints 3381-3383 of 4770")
	)
	(layers
		(0 "F.Cu" signal "TOP")
		(4 "In1.Cu" signal "L2GND")
		(6 "In2.Cu" signal "L3")
		(8 "In3.Cu" signal "L4GND")
		(10 "In4.Cu" signal "L5")
		(12 "In5.Cu" signal "L6GND")
		(14 "In6.Cu" signal "L7VCC")
		(16 "In7.Cu" signal "L8VCC")
		(18 "In8.Cu" signal "L9GND")
		(20 "In9.Cu" signal "L10")
		(22 "In10.Cu" signal "L11GND")
		(24 "In11.Cu" signal "L12")
		(26 "In12.Cu" signal "L13GND")
		(2 "B.Cu" signal "BOTTOM")
		(9 "F.Adhes" user "F.Adhesive")
		(11 "B.Adhes" user "B.Adhesive")
		(13 "F.Paste" user "Package Geometry/Pastemask Top")
		(15 "B.Paste" user "Package Geometry/Pastemask Bottom")
		(5 "F.SilkS" user "Ref Des/Silkscreen Top")
		(7 "B.SilkS" user "Ref Des/Silkscreen Bottom")
		(1 "F.Mask" user "Board Geometry/Soldermask Top")
		(3 "B.Mask" user "Board Geometry/Soldermask Bottom")
		(17 "Dwgs.User" user "User.Drawings")
		(19 "Cmts.User" user "User.Comments")
		(21 "Eco1.User" user "User.Eco1")
		(23 "Eco2.User" user "User.Eco2")
		(25 "Edge.Cuts" user "Board Geometry/Outline")
		(27 "Margin" user)
		(31 "F.CrtYd" user "Package Geometry/Place Bound Top")
		(29 "B.CrtYd" user "Package Geometry/Place Bound Bottom")
		(35 "F.Fab" user "Ref Des/Assembly Top")
		(33 "B.Fab" user "Ref Des/Assembly Bottom")
	)
	(footprint ""
		(layer "B.Cu")
		(at 465.328 -116.49202)
		(property "Reference" "C1M7"
			(at 0 0 0)
			(layer "B.SilkS")
			(hide yes)
			(effects
				(font
					(size 1.27 1.27)
				)
				(justify mirror)
			)
		)
		(property "Value" ""
			(at 0 0 0)
			(layer "B.Fab")
			(effects
				(font
					(size 1.27 1.27)
				)
				(justify mirror)
			)
		)
		(duplicate_pad_numbers_are_jumpers no)
		(fp_rect
			(start -0.3048 0.9906)
			(end 0.3048 -0.1016)
			(stroke
				(width 0)
				(type default)
			)
			(fill no)
			(layer "B.CrtYd")
		)
		(fp_line
			(start -0.3048 -0.1016)
			(end 0.3048 -0.1016)
			(stroke
				(width 0.1)
				(type default)
			)
			(layer "B.Fab")
		)
		(fp_line
			(start -0.3048 0.9906)
			(end -0.3048 -0.1016)
			(stroke
				(width 0.1)
				(type default)
			)
			(layer "B.Fab")
		)
		(fp_line
			(start 0.3048 -0.1016)
			(end 0.3048 0.9906)
			(stroke
				(width 0.1)
				(type default)
			)
			(layer "B.Fab")
		)
		(fp_line
			(start 0.3048 0.9906)
			(end -0.3048 0.9906)
			(stroke
				(width 0.1)
				(type default)
			)
			(layer "B.Fab")
		)
		(pad "1" smd rect
			(at 0 0 180)
			(size 0.508 0.508)
			(layers "B.Cu" "B.Mask" "B.Paste")
			(net "P3E_CPU0_PE3_OCP_TXN<15>")
		)
		(pad "2" smd rect
			(at 0 0.889 180)
			(size 0.508 0.508)
			(layers "B.Cu" "B.Mask" "B.Paste")
			(net "P3E_OCP_CPU0_PE3_C_TXN<15>")
		)
		(zone
			(layer "B.Cu")
			(hatch none 0.5)
			(connect_pads
				(clearance 0)
			)
			(min_thickness 0.25)
			(keepout
				(tracks allowed)
				(vias not_allowed)
				(pads allowed)
				(copperpour not_allowed)
				(footprints allowed)
			)
			(placement
				(enabled no)
				(sheetname "")
			)
			(fill
				(thermal_gap 0.5)
				(thermal_bridge_width 0.5)
				(island_removal_mode 0)
			)
			(polygon
				(pts
					(xy 465.074 -115.85702) (xy 465.582 -115.85702) (xy 465.582 -116.23802) (xy 465.074 -116.23802)
				)
			)
		)
		(zone
			(layer "B.Cu")
			(hatch none 0.5)
			(connect_pads
				(clearance 0)
			)
			(min_thickness 0.25)
			(keepout
				(tracks not_allowed)
				(vias allowed)
				(pads allowed)
				(copperpour not_allowed)
				(footprints allowed)
			)
			(placement
				(enabled no)
				(sheetname "")
			)
			(fill
				(thermal_gap 0.5)
				(thermal_bridge_width 0.5)
				(island_removal_mode 0)
			)
			(polygon
				(pts
					(xy 465.074 -115.85702) (xy 465.582 -115.85702) (xy 465.582 -116.23802) (xy 465.074 -116.23802)
				)
			)
		)
	)
	(footprint ""
		(layer "B.Cu")
		(at 450.2277 -148.59 -90)
		(property "Reference" "C25W93"
			(at 0.8382 -0.67818 270)
			(unlocked yes)
			(layer "B.SilkS")
			(effects
				(font
					(size 0.4064 0.254)
					(thickness 0.1524)
				)
				(justify left mirror)
			)
		)
		(property "Value" ""
			(at 0 0 90)
			(layer "B.Fab")
			(effects
				(font
					(size 1.27 1.27)
				)
				(justify mirror)
			)
		)
		(duplicate_pad_numbers_are_jumpers no)
		(fp_poly
			(pts
				(xy -0.3048 -0.1016) (xy -0.3048 0.9906) (xy 0.3048 0.9906) (xy 0.3048 -0.1016)
			)
			(stroke
				(width 0)
				(type default)
			)
			(fill no)
			(layer "B.CrtYd")
		)
		(fp_line
			(start -0.3048 0.9906)
			(end -0.3048 -0.1016)
			(stroke
				(width 0.1)
				(type default)
			)
			(layer "B.Fab")
		)
		(fp_line
			(start 0.3048 0.9906)
			(end -0.3048 0.9906)
			(stroke
				(width 0.1)
				(type default)
			)
			(layer "B.Fab")
		)
		(fp_line
			(start -0.3048 -0.1016)
			(end 0.3048 -0.1016)
			(stroke
				(width 0.1)
				(type default)
			)
			(layer "B.Fab")
		)
		(fp_line
			(start 0.3048 -0.1016)
			(end 0.3048 0.9906)
			(stroke
				(width 0.1)
				(type default)
			)
			(layer "B.Fab")
		)
		(pad "1" smd rect
			(at 0 0 90)
			(size 0.508 0.508)
			(layers "B.Cu" "B.Mask" "B.Paste")
			(net "P0V7_GTL2014_VREF_6")
		)
		(pad "2" smd rect
			(at 0 0.889 90)
			(size 0.508 0.508)
			(layers "B.Cu" "B.Mask" "B.Paste")
			(net "GND")
		)
		(zone
			(layer "B.Cu")
			(hatch none 0.5)
			(connect_pads
				(clearance 0)
			)
			(min_thickness 0.25)
			(keepout
				(tracks not_allowed)
				(vias allowed)
				(pads allowed)
				(copperpour not_allowed)
				(footprints allowed)
			)
			(placement
				(enabled no)
				(sheetname "")
			)
			(fill
				(thermal_gap 0.5)
				(thermal_bridge_width 0.5)
				(island_removal_mode 0)
			)
			(polygon
				(pts
					(xy 449.5927 -148.336) (xy 449.5927 -148.844) (xy 449.9737 -148.844) (xy 449.9737 -148.336)
				)
			)
		)
		(zone
			(layer "B.Cu")
			(hatch none 0.5)
			(connect_pads
				(clearance 0)
			)
			(min_thickness 0.25)
			(keepout
				(tracks allowed)
				(vias not_allowed)
				(pads allowed)
				(copperpour not_allowed)
				(footprints allowed)
			)
			(placement
				(enabled no)
				(sheetname "")
			)
			(fill
				(thermal_gap 0.5)
				(thermal_bridge_width 0.5)
				(island_removal_mode 0)
			)
			(polygon
				(pts
					(xy 449.9737 -148.336) (xy 449.9737 -148.844) (xy 449.5927 -148.844) (xy 449.5927 -148.336)
				)
			)
		)
	)
	(footprint ""
		(layer "B.Cu")
		(at 330.08316 -67.26936 90)
		(property "Reference" "R4P15"
			(at 0 0 90)
			(layer "B.SilkS")
			(hide yes)
			(effects
				(font
					(size 1.27 1.27)
				)
				(justify mirror)
			)
		)
		(property "Value" ""
			(at 0 0 90)
			(layer "B.Fab")
			(effects
				(font
					(size 1.27 1.27)
				)
				(justify mirror)
			)
		)
		(duplicate_pad_numbers_are_jumpers no)
		(fp_poly
			(pts
				(xy 0.2794 -0.1016) (xy -0.2794 -0.1016) (xy -0.2794 0.9906) (xy 0.2794 0.9906)
			)
			(stroke
				(width 0)
				(type default)
			)
			(fill no)
			(layer "B.CrtYd")
		)
		(fp_line
			(start 0.2794 -0.1016)
			(end 0.2794 0.9906)
			(stroke
				(width 0.1)
				(type default)
			)
			(layer "B.Fab")
		)
		(fp_line
			(start -0.2794 -0.1016)
			(end 0.2794 -0.1016)
			(stroke
				(width 0.1)
				(type default)
			)
			(layer "B.Fab")
		)
		(fp_line
			(start 0.2794 0.9906)
			(end -0.2794 0.9906)
			(stroke
				(width 0.1)
				(type default)
			)
			(layer "B.Fab")
		)
		(fp_line
			(start -0.2794 0.9906)
			(end -0.2794 -0.1016)
			(stroke
				(width 0.1)
				(type default)
			)
			(layer "B.Fab")
		)
		(pad "1" smd rect
			(at 0 0 270)
			(size 0.508 0.508)
			(layers "B.Cu" "B.Mask" "B.Paste")
			(net "PVCCIO_CPU0")
		)
		(pad "2" smd rect
			(at 0 0.889 270)
			(size 0.508 0.508)
			(layers "B.Cu" "B.Mask" "B.Paste")
			(net "XDP_CPU_MBP1_N")
		)
		(zone
			(layer "B.Cu")
			(hatch none 0.5)
			(connect_pads
				(clearance 0)
			)
			(min_thickness 0.25)
			(keepout
				(tracks allowed)
				(vias not_allowed)
				(pads allowed)
				(copperpour not_allowed)
				(footprints allowed)
			)
			(placement
				(enabled no)
				(sheetname "")
			)
			(fill
				(thermal_gap 0.5)
				(thermal_bridge_width 0.5)
				(island_removal_mode 0)
			)
			(polygon
				(pts
					(xy 330.33716 -67.52336) (xy 330.33716 -67.01536) (xy 330.71816 -67.01536) (xy 330.71816 -67.52336)
				)
			)
		)
		(zone
			(layer "B.Cu")
			(hatch none 0.5)
			(connect_pads
				(clearance 0)
			)
			(min_thickness 0.25)
			(keepout
				(tracks not_allowed)
				(vias allowed)
				(pads allowed)
				(copperpour not_allowed)
				(footprints allowed)
			)
			(placement
				(enabled no)
				(sheetname "")
			)
			(fill
				(thermal_gap 0.5)
				(thermal_bridge_width 0.5)
				(island_removal_mode 0)
			)
			(polygon
				(pts
					(xy 330.71816 -67.52336) (xy 330.71816 -67.01536) (xy 330.33716 -67.01536) (xy 330.33716 -67.52336)
				)
			)
		)
	)
)
